# T6G (Grand Teton) — schematic netlist excerpt (pin names and nets, part order shuffled) for the footprints in the layout excerpt that follows; sources: Cadence DE-HDL packaged netlist, KiCad conversion of 04192023_DAF0TMB3IC0_F0TG_MB_C_brd_V02_OCP.brd

PC534  Q_CAPP  470UF 2.5V 20% SPCAP  pkg SMLF  page 363 : A = P0V9_CPU0_RT_2D ; B = GND
PR6610  Q_RES  0 5% CHIP  pkg 0402LF  page 362 : A = NC_P0V9_RETIMER_CPU0_IMON4 ; B = GND

(kicad_pcb
	(version 20260206)
	(generator "pcbnew")
	(generator_version "10.0")
	(general
		(thickness 1.6)
		(legacy_teardrops no)
	)
	(paper "A4")
	(title_block
		(title "04192023_DAF0TMB3IC0_F0TG_MB_C_brd_V02_OCP.brd")
		(comment 1 "Grand Teton / footprints 7922-7923 of 8354")
	)
	(layers
		(0 "F.Cu" signal "TOP")
		(4 "In1.Cu" signal "GND")
		(6 "In2.Cu" signal "IN1")
		(8 "In3.Cu" signal "GND1")
		(10 "In4.Cu" signal "IN2")
		(12 "In5.Cu" signal "GND2")
		(14 "In6.Cu" signal "IN3")
		(16 "In7.Cu" signal "GND3")
		(18 "In8.Cu" signal "VCC")
		(20 "In9.Cu" signal "VCC1")
		(22 "In10.Cu" signal "GND4")
		(24 "In11.Cu" signal "IN4")
		(26 "In12.Cu" signal "GND5")
		(28 "In13.Cu" signal "IN5")
		(30 "In14.Cu" signal "GND6")
		(32 "In15.Cu" signal "IN6")
		(34 "In16.Cu" signal "GND7")
		(2 "B.Cu" signal "BOTTOM")
		(9 "F.Adhes" user "F.Adhesive")
		(11 "B.Adhes" user "B.Adhesive")
		(13 "F.Paste" user "Package Geometry/Pastemask Top")
		(15 "B.Paste" user "Package Geometry/Pastemask Bottom")
		(5 "F.SilkS" user "Ref Des/Silkscreen Top")
		(7 "B.SilkS" user "Ref Des/Silkscreen Bottom")
		(1 "F.Mask" user "Board Geometry/Soldermask Top")
		(3 "B.Mask" user "Board Geometry/Soldermask Bottom")
		(17 "Dwgs.User" user "User.Drawings")
		(19 "Cmts.User" user "User.Comments")
		(21 "Eco1.User" user "User.Eco1")
		(23 "Eco2.User" user "User.Eco2")
		(25 "Edge.Cuts" user "Board Geometry/Outline")
		(27 "Margin" user)
		(31 "F.CrtYd" user "Package Geometry/Place Bound Top")
		(29 "B.CrtYd" user "Package Geometry/Place Bound Bottom")
		(35 "F.Fab" user "Ref Des/Assembly Top")
		(33 "B.Fab" user "Ref Des/Assembly Bottom")
	)
	(footprint ""
		(layer "B.Cu")
		(at 444.617602 -418.58311 90)
		(property "Reference" "PR6610"
			(at 0 0 90)
			(layer "B.SilkS")
			(hide yes)
			(effects
				(font
					(size 1.27 1.27)
				)
				(justify mirror)
			)
		)
		(property "Value" ""
			(at 0 0 90)
			(layer "B.Fab")
			(effects
				(font
					(size 1.27 1.27)
				)
				(justify mirror)
			)
		)
		(duplicate_pad_numbers_are_jumpers no)
		(fp_line
			(start 0.7874 -0.4064)
			(end -0.7874 -0.4064)
			(stroke
				(width 0.1524)
				(type default)
			)
			(layer "B.SilkS")
		)
		(fp_line
			(start -0.7874 -0.4064)
			(end -0.7874 0.4064)
			(stroke
				(width 0.1524)
				(type default)
			)
			(layer "B.SilkS")
		)
		(fp_line
			(start 0.7874 0.4064)
			(end 0.7874 -0.4064)
			(stroke
				(width 0.1524)
				(type default)
			)
			(layer "B.SilkS")
		)
		(fp_line
			(start -0.7874 0.4064)
			(end 0.7874 0.4064)
			(stroke
				(width 0.1524)
				(type default)
			)
			(layer "B.SilkS")
		)
		(fp_line
			(start 0.67945 -0.305054)
			(end 0.12065 -0.305054)
			(stroke
				(width 0.1)
				(type default)
			)
			(layer "B.Fab")
		)
		(fp_line
			(start 0.12065 -0.305054)
			(end 0.12065 -0.2794)
			(stroke
				(width 0.1)
				(type default)
			)
			(layer "B.Fab")
		)
		(fp_line
			(start -0.12065 -0.3048)
			(end -0.67945 -0.3048)
			(stroke
				(width 0.1)
				(type default)
			)
			(layer "B.Fab")
		)
		(fp_line
			(start -0.67945 -0.3048)
			(end -0.67945 0.3048)
			(stroke
				(width 0.1)
				(type default)
			)
			(layer "B.Fab")
		)
		(fp_line
			(start 0.12065 -0.2794)
			(end -0.12065 -0.2794)
			(stroke
				(width 0.1)
				(type default)
			)
			(layer "B.Fab")
		)
		(fp_line
			(start -0.12065 -0.2794)
			(end -0.12065 -0.3048)
			(stroke
				(width 0.1)
				(type default)
			)
			(layer "B.Fab")
		)
		(fp_line
			(start 0.12065 0.2794)
			(end 0.12065 0.3048)
			(stroke
				(width 0.1)
				(type default)
			)
			(layer "B.Fab")
		)
		(fp_line
			(start -0.120396 0.2794)
			(end 0.12065 0.2794)
			(stroke
				(width 0.1)
				(type default)
			)
			(layer "B.Fab")
		)
		(fp_line
			(start 0.67945 0.3048)
			(end 0.67945 -0.305054)
			(stroke
				(width 0.1)
				(type default)
			)
			(layer "B.Fab")
		)
		(fp_line
			(start 0.12065 0.3048)
			(end 0.67945 0.3048)
			(stroke
				(width 0.1)
				(type default)
			)
			(layer "B.Fab")
		)
		(fp_line
			(start -0.120396 0.3048)
			(end -0.120396 0.2794)
			(stroke
				(width 0.1)
				(type default)
			)
			(layer "B.Fab")
		)
		(fp_line
			(start -0.67945 0.3048)
			(end -0.120396 0.3048)
			(stroke
				(width 0.1)
				(type default)
			)
			(layer "B.Fab")
		)
		(pad "1" smd circle
			(at 0.40005 0 270)
			(size 0 0)
			(layers "B.Cu" "B.Mask" "B.Paste")
			(net "NC_P0V9_RETIMER_CPU0_IMON4")
		)
		(pad "2" smd circle
			(at -0.40005 0 270)
			(size 0 0)
			(layers "B.Cu" "B.Mask" "B.Paste")
			(net "GND")
		)
	)
	(footprint ""
		(layer "B.Cu")
		(at 462.124552 -380.027434 90)
		(property "Reference" "PC534"
			(at -6.293104 1.933448 0)
			(unlocked yes)
			(layer "B.SilkS")
			(effects
				(font
					(size 0.7874 0.5842)
					(thickness 0.1524)
				)
				(justify left mirror)
			)
		)
		(property "Value" ""
			(at 0 0 90)
			(layer "B.Fab")
			(effects
				(font
					(size 1.27 1.27)
				)
				(justify mirror)
			)
		)
		(duplicate_pad_numbers_are_jumpers no)
		(fp_line
			(start 4.84378 -2.150618)
			(end 4.53898 -2.150618)
			(stroke
				(width 0.1524)
				(type default)
			)
			(layer "B.SilkS")
		)
		(fp_line
			(start 4.84378 -2.150618)
			(end 4.842256 2.163064)
			(stroke
				(width 0.1524)
				(type default)
			)
			(layer "B.SilkS")
		)
		(fp_line
			(start 4.69138 -2.150618)
			(end 4.692396 2.161032)
			(stroke
				(width 0.1524)
				(type default)
			)
			(layer "B.SilkS")
		)
		(fp_line
			(start 4.53898 -2.150618)
			(end 4.539742 2.152142)
			(stroke
				(width 0.1524)
				(type default)
			)
			(layer "B.SilkS")
		)
		(fp_line
			(start 4.53898 -2.15011)
			(end -4.53898 -2.15011)
			(stroke
				(width 0.1524)
				(type default)
			)
			(layer "B.SilkS")
		)
		(fp_line
			(start -4.53898 -2.15011)
			(end -4.53898 1.882648)
			(stroke
				(width 0.1524)
				(type default)
			)
			(layer "B.SilkS")
		)
		(fp_line
			(start 4.53898 2.15011)
			(end 4.53898 -2.15011)
			(stroke
				(width 0.1524)
				(type default)
			)
			(layer "B.SilkS")
		)
		(fp_line
			(start -4.056634 2.15011)
			(end 4.53898 2.15011)
			(stroke
				(width 0.1524)
				(type default)
			)
			(layer "B.SilkS")
		)
		(fp_line
			(start 4.83108 2.150364)
			(end 4.447794 2.149348)
			(stroke
				(width 0.1524)
				(type default)
			)
			(layer "B.SilkS")
		)
		(fp_line
			(start 3.64998 -2.15011)
			(end -3.64998 -2.15011)
			(stroke
				(width 0.1)
				(type default)
			)
			(layer "B.Fab")
		)
		(fp_line
			(start -3.64998 -2.15011)
			(end -3.64998 2.15011)
			(stroke
				(width 0.1)
				(type default)
			)
			(layer "B.Fab")
		)
		(fp_line
			(start 3.64998 2.15011)
			(end 3.64998 -2.15011)
			(stroke
				(width 0.1)
				(type default)
			)
			(layer "B.Fab")
		)
		(fp_line
			(start -3.64998 2.15011)
			(end 3.64998 2.15011)
			(stroke
				(width 0.1)
				(type default)
			)
			(layer "B.Fab")
		)
		(fp_text user "+"
			(at 6.214872 -0.337058 90)
			(unlocked yes)
			(layer "B.SilkS")
			(effects
				(font
					(size 1.905 1.4224)
					(thickness 0.1524)
				)
				(justify left mirror)
			)
		)
		(fp_text user "-"
			(at -4.313174 -0.094488 90)
			(unlocked yes)
			(layer "B.SilkS")
			(effects
				(font
					(size 1.905 1.4224)
					(thickness 0.1524)
				)
				(justify left mirror)
			)
		)
		(fp_text user "+"
			(at 6.214872 -0.337058 90)
			(unlocked yes)
			(layer "B.Fab")
			(effects
				(font
					(size 1.905 1.4224)
					(thickness 0.1524)
				)
				(justify left mirror)
			)
		)
		(fp_text user "-"
			(at -4.313174 -0.094488 90)
			(unlocked yes)
			(layer "B.Fab")
			(effects
				(font
					(size 1.905 1.4224)
					(thickness 0.1524)
				)
				(justify left mirror)
			)
		)
		(pad "1" smd rect
			(at 3.199892 0 270)
			(size 2.413 2.8194)
			(layers "B.Cu" "B.Mask" "B.Paste")
			(net "P0V9_CPU0_RT_2D")
		)
		(pad "2" smd rect
			(at -3.199892 0 270)
			(size 2.413 2.8194)
			(layers "B.Cu" "B.Mask" "B.Paste")
			(net "GND")
		)
	)
)
